# S9S_MB_2U (Grand Teton) — schematic netlist excerpt (pin names and nets, part order shuffled) for the footprints in the layout excerpt that follows; sources: Cadence DE-HDL packaged netlist, KiCad conversion of 03242023_DA0F0TMBIJ0_F0T_Motherboard_J_brd_V01_OCP.brd

PR3790  Q_RES  7.15K 1% CHIP  pkg 0402LF  page 156 : A = P3V3_OCP_UV_1 ; B = P3V3_OCP_OV_1
C593  Q_CAP  0.1UF 25V 10% X7R  pkg 0402  page 156 : A = P3V3_AUX ; B = GND

(kicad_pcb
	(version 20260206)
	(generator "pcbnew")
	(generator_version "10.0")
	(general
		(thickness 1.6)
		(legacy_teardrops no)
	)
	(paper "A4")
	(title_block
		(title "03242023_DA0F0TMBIJ0_F0T_Motherboard_J_brd_V01_OCP.brd")
		(comment 1 "Grand Teton / footprints 1414-1415 of 6105")
	)
	(layers
		(0 "F.Cu" signal "TOP")
		(4 "In1.Cu" signal "GND")
		(6 "In2.Cu" signal "IN1")
		(8 "In3.Cu" signal "GND1")
		(10 "In4.Cu" signal "IN2")
		(12 "In5.Cu" signal "GND2")
		(14 "In6.Cu" signal "IN3")
		(16 "In7.Cu" signal "GND3")
		(18 "In8.Cu" signal "VCC")
		(20 "In9.Cu" signal "VCC1")
		(22 "In10.Cu" signal "GND4")
		(24 "In11.Cu" signal "IN4")
		(26 "In12.Cu" signal "GND5")
		(28 "In13.Cu" signal "IN5")
		(30 "In14.Cu" signal "GND6")
		(32 "In15.Cu" signal "IN6")
		(34 "In16.Cu" signal "GND7")
		(2 "B.Cu" signal "BOTTOM")
		(9 "F.Adhes" user "F.Adhesive")
		(11 "B.Adhes" user "B.Adhesive")
		(13 "F.Paste" user "Package Geometry/Pastemask Top")
		(15 "B.Paste" user "Package Geometry/Pastemask Bottom")
		(5 "F.SilkS" user "Ref Des/Silkscreen Top")
		(7 "B.SilkS" user "Ref Des/Silkscreen Bottom")
		(1 "F.Mask" user "Board Geometry/Soldermask Top")
		(3 "B.Mask" user "Board Geometry/Soldermask Bottom")
		(17 "Dwgs.User" user "User.Drawings")
		(19 "Cmts.User" user "User.Comments")
		(21 "Eco1.User" user "User.Eco1")
		(23 "Eco2.User" user "User.Eco2")
		(25 "Edge.Cuts" user "Board Geometry/Outline")
		(27 "Margin" user)
		(31 "F.CrtYd" user "Package Geometry/Place Bound Top")
		(29 "B.CrtYd" user "Package Geometry/Place Bound Bottom")
		(35 "F.Fab" user "Ref Des/Assembly Top")
		(33 "B.Fab" user "Ref Des/Assembly Bottom")
	)
	(footprint ""
		(layer "F.Cu")
		(at 428.912782 -107.872276 180)
		(property "Reference" "PR3790"
			(at 0 0 180)
			(layer "F.SilkS")
			(hide yes)
			(effects
				(font
					(size 1.27 1.27)
				)
			)
		)
		(property "Value" ""
			(at 0 0 180)
			(layer "F.Fab")
			(effects
				(font
					(size 1.27 1.27)
				)
			)
		)
		(duplicate_pad_numbers_are_jumpers no)
		(fp_line
			(start 0.7874 0.4064)
			(end -0.7874 0.4064)
			(stroke
				(width 0.1524)
				(type default)
			)
			(layer "F.SilkS")
		)
		(fp_line
			(start 0.7874 -0.4064)
			(end 0.7874 0.4064)
			(stroke
				(width 0.1524)
				(type default)
			)
			(layer "F.SilkS")
		)
		(fp_line
			(start -0.7874 0.4064)
			(end -0.7874 -0.4064)
			(stroke
				(width 0.1524)
				(type default)
			)
			(layer "F.SilkS")
		)
		(fp_line
			(start -0.7874 -0.4064)
			(end 0.7874 -0.4064)
			(stroke
				(width 0.1524)
				(type default)
			)
			(layer "F.SilkS")
		)
		(fp_line
			(start 0.67945 0.3048)
			(end 0.120396 0.3048)
			(stroke
				(width 0.1)
				(type default)
			)
			(layer "F.Fab")
		)
		(fp_line
			(start 0.67945 -0.3048)
			(end 0.67945 0.3048)
			(stroke
				(width 0.1)
				(type default)
			)
			(layer "F.Fab")
		)
		(fp_line
			(start 0.12065 -0.2794)
			(end 0.12065 -0.3048)
			(stroke
				(width 0.1)
				(type default)
			)
			(layer "F.Fab")
		)
		(fp_line
			(start 0.12065 -0.3048)
			(end 0.67945 -0.3048)
			(stroke
				(width 0.1)
				(type default)
			)
			(layer "F.Fab")
		)
		(fp_line
			(start 0.120396 0.3048)
			(end 0.120396 0.2794)
			(stroke
				(width 0.1)
				(type default)
			)
			(layer "F.Fab")
		)
		(fp_line
			(start 0.120396 0.2794)
			(end -0.12065 0.2794)
			(stroke
				(width 0.1)
				(type default)
			)
			(layer "F.Fab")
		)
		(fp_line
			(start -0.12065 0.3048)
			(end -0.67945 0.3048)
			(stroke
				(width 0.1)
				(type default)
			)
			(layer "F.Fab")
		)
		(fp_line
			(start -0.12065 0.2794)
			(end -0.12065 0.3048)
			(stroke
				(width 0.1)
				(type default)
			)
			(layer "F.Fab")
		)
		(fp_line
			(start -0.12065 -0.2794)
			(end 0.12065 -0.2794)
			(stroke
				(width 0.1)
				(type default)
			)
			(layer "F.Fab")
		)
		(fp_line
			(start -0.12065 -0.305054)
			(end -0.12065 -0.2794)
			(stroke
				(width 0.1)
				(type default)
			)
			(layer "F.Fab")
		)
		(fp_line
			(start -0.67945 0.3048)
			(end -0.67945 -0.305054)
			(stroke
				(width 0.1)
				(type default)
			)
			(layer "F.Fab")
		)
		(fp_line
			(start -0.67945 -0.305054)
			(end -0.12065 -0.305054)
			(stroke
				(width 0.1)
				(type default)
			)
			(layer "F.Fab")
		)
		(pad "1" smd circle
			(at -0.40005 0 180)
			(size 0 0)
			(layers "F.Cu" "F.Mask" "F.Paste")
			(net "P3V3_OCP_UV_1")
		)
		(pad "2" smd circle
			(at 0.40005 0 180)
			(size 0 0)
			(layers "F.Cu" "F.Mask" "F.Paste")
			(net "P3V3_OCP_OV_1")
		)
	)
	(footprint ""
		(layer "F.Cu")
		(at 461.720946 -103.614728)
		(property "Reference" "C593"
			(at 0 0 0)
			(layer "F.SilkS")
			(hide yes)
			(effects
				(font
					(size 1.27 1.27)
				)
			)
		)
		(property "Value" ""
			(at 0 0 0)
			(layer "F.Fab")
			(effects
				(font
					(size 1.27 1.27)
				)
			)
		)
		(duplicate_pad_numbers_are_jumpers no)
		(fp_line
			(start -0.7874 -0.4064)
			(end 0.7874 -0.4064)
			(stroke
				(width 0.1524)
				(type default)
			)
			(layer "F.SilkS")
		)
		(fp_line
			(start -0.7874 0.4064)
			(end -0.7874 -0.4064)
			(stroke
				(width 0.1524)
				(type default)
			)
			(layer "F.SilkS")
		)
		(fp_line
			(start 0.7874 -0.4064)
			(end 0.7874 0.4064)
			(stroke
				(width 0.1524)
				(type default)
			)
			(layer "F.SilkS")
		)
		(fp_line
			(start 0.7874 0.4064)
			(end -0.7874 0.4064)
			(stroke
				(width 0.1524)
				(type default)
			)
			(layer "F.SilkS")
		)
		(fp_line
			(start -0.67945 -0.305054)
			(end -0.12065 -0.305054)
			(stroke
				(width 0.1)
				(type default)
			)
			(layer "F.Fab")
		)
		(fp_line
			(start -0.67945 0.3048)
			(end -0.67945 -0.305054)
			(stroke
				(width 0.1)
				(type default)
			)
			(layer "F.Fab")
		)
		(fp_line
			(start -0.12065 -0.305054)
			(end -0.12065 -0.2794)
			(stroke
				(width 0.1)
				(type default)
			)
			(layer "F.Fab")
		)
		(fp_line
			(start -0.12065 -0.2794)
			(end 0.12065 -0.2794)
			(stroke
				(width 0.1)
				(type default)
			)
			(layer "F.Fab")
		)
		(fp_line
			(start -0.12065 0.2794)
			(end -0.12065 0.3048)
			(stroke
				(width 0.1)
				(type default)
			)
			(layer "F.Fab")
		)
		(fp_line
			(start -0.12065 0.3048)
			(end -0.67945 0.3048)
			(stroke
				(width 0.1)
				(type default)
			)
			(layer "F.Fab")
		)
		(fp_line
			(start 0.120396 0.2794)
			(end -0.12065 0.2794)
			(stroke
				(width 0.1)
				(type default)
			)
			(layer "F.Fab")
		)
		(fp_line
			(start 0.120396 0.3048)
			(end 0.120396 0.2794)
			(stroke
				(width 0.1)
				(type default)
			)
			(layer "F.Fab")
		)
		(fp_line
			(start 0.12065 -0.3048)
			(end 0.67945 -0.3048)
			(stroke
				(width 0.1)
				(type default)
			)
			(layer "F.Fab")
		)
		(fp_line
			(start 0.12065 -0.2794)
			(end 0.12065 -0.3048)
			(stroke
				(width 0.1)
				(type default)
			)
			(layer "F.Fab")
		)
		(fp_line
			(start 0.67945 -0.3048)
			(end 0.67945 0.3048)
			(stroke
				(width 0.1)
				(type default)
			)
			(layer "F.Fab")
		)
		(fp_line
			(start 0.67945 0.3048)
			(end 0.120396 0.3048)
			(stroke
				(width 0.1)
				(type default)
			)
			(layer "F.Fab")
		)
		(pad "1" smd circle
			(at -0.40005 0)
			(size 0 0)
			(layers "F.Cu" "F.Mask" "F.Paste")
			(net "P3V3_AUX")
		)
		(pad "2" smd circle
			(at 0.40005 0)
			(size 0 0)
			(layers "F.Cu" "F.Mask" "F.Paste")
			(net "GND")
		)
	)
)
